# T6G (Grand Teton) — schematic netlist excerpt (pin names and nets, part order shuffled) for the footprints in the layout excerpt that follows; sources: Cadence DE-HDL packaged netlist, KiCad conversion of 04192023_DAF0TMB3IC0_F0TG_MB_C_brd_V02_OCP.brd

PC357  Q_CAP  0.1UF 25V 10% X7R  pkg 0402  page 217 : A = PVDDCR_CPU1_P1_VMON ; B = GND
PR6626  Q_RES  0 5% CHIP  pkg 0402LF  page 365 : A = P0V9_RETIMER_CPU1_VOS1 ; B = P0V9_CPU1_RT_2D

(kicad_pcb
	(version 20260206)
	(generator "pcbnew")
	(generator_version "10.0")
	(general
		(thickness 1.6)
		(legacy_teardrops no)
	)
	(paper "A4")
	(title_block
		(title "04192023_DAF0TMB3IC0_F0TG_MB_C_brd_V02_OCP.brd")
		(comment 1 "Grand Teton / footprints 1518-1519 of 8354")
	)
	(layers
		(0 "F.Cu" signal "TOP")
		(4 "In1.Cu" signal "GND")
		(6 "In2.Cu" signal "IN1")
		(8 "In3.Cu" signal "GND1")
		(10 "In4.Cu" signal "IN2")
		(12 "In5.Cu" signal "GND2")
		(14 "In6.Cu" signal "IN3")
		(16 "In7.Cu" signal "GND3")
		(18 "In8.Cu" signal "VCC")
		(20 "In9.Cu" signal "VCC1")
		(22 "In10.Cu" signal "GND4")
		(24 "In11.Cu" signal "IN4")
		(26 "In12.Cu" signal "GND5")
		(28 "In13.Cu" signal "IN5")
		(30 "In14.Cu" signal "GND6")
		(32 "In15.Cu" signal "IN6")
		(34 "In16.Cu" signal "GND7")
		(2 "B.Cu" signal "BOTTOM")
		(9 "F.Adhes" user "F.Adhesive")
		(11 "B.Adhes" user "B.Adhesive")
		(13 "F.Paste" user "Package Geometry/Pastemask Top")
		(15 "B.Paste" user "Package Geometry/Pastemask Bottom")
		(5 "F.SilkS" user "Ref Des/Silkscreen Top")
		(7 "B.SilkS" user "Ref Des/Silkscreen Bottom")
		(1 "F.Mask" user "Board Geometry/Soldermask Top")
		(3 "B.Mask" user "Board Geometry/Soldermask Bottom")
		(17 "Dwgs.User" user "User.Drawings")
		(19 "Cmts.User" user "User.Comments")
		(21 "Eco1.User" user "User.Eco1")
		(23 "Eco2.User" user "User.Eco2")
		(25 "Edge.Cuts" user "Board Geometry/Outline")
		(27 "Margin" user)
		(31 "F.CrtYd" user "Package Geometry/Place Bound Top")
		(29 "B.CrtYd" user "Package Geometry/Place Bound Bottom")
		(35 "F.Fab" user "Ref Des/Assembly Top")
		(33 "B.Fab" user "Ref Des/Assembly Bottom")
	)
	(footprint ""
		(layer "F.Cu")
		(at 37.211 -365.125)
		(property "Reference" "PC357"
			(at 0 0 0)
			(layer "F.SilkS")
			(hide yes)
			(effects
				(font
					(size 1.27 1.27)
				)
			)
		)
		(property "Value" ""
			(at 0 0 0)
			(layer "F.Fab")
			(effects
				(font
					(size 1.27 1.27)
				)
			)
		)
		(duplicate_pad_numbers_are_jumpers no)
		(fp_line
			(start -0.7874 -0.4064)
			(end 0.7874 -0.4064)
			(stroke
				(width 0.1524)
				(type default)
			)
			(layer "F.SilkS")
		)
		(fp_line
			(start -0.7874 0.4064)
			(end -0.7874 -0.4064)
			(stroke
				(width 0.1524)
				(type default)
			)
			(layer "F.SilkS")
		)
		(fp_line
			(start 0.7874 -0.4064)
			(end 0.7874 0.4064)
			(stroke
				(width 0.1524)
				(type default)
			)
			(layer "F.SilkS")
		)
		(fp_line
			(start 0.7874 0.4064)
			(end -0.7874 0.4064)
			(stroke
				(width 0.1524)
				(type default)
			)
			(layer "F.SilkS")
		)
		(fp_line
			(start -0.67945 -0.305054)
			(end -0.12065 -0.305054)
			(stroke
				(width 0.1)
				(type default)
			)
			(layer "F.Fab")
		)
		(fp_line
			(start -0.67945 0.3048)
			(end -0.67945 -0.305054)
			(stroke
				(width 0.1)
				(type default)
			)
			(layer "F.Fab")
		)
		(fp_line
			(start -0.12065 -0.305054)
			(end -0.12065 -0.2794)
			(stroke
				(width 0.1)
				(type default)
			)
			(layer "F.Fab")
		)
		(fp_line
			(start -0.12065 -0.2794)
			(end 0.12065 -0.2794)
			(stroke
				(width 0.1)
				(type default)
			)
			(layer "F.Fab")
		)
		(fp_line
			(start -0.12065 0.2794)
			(end -0.12065 0.3048)
			(stroke
				(width 0.1)
				(type default)
			)
			(layer "F.Fab")
		)
		(fp_line
			(start -0.12065 0.3048)
			(end -0.67945 0.3048)
			(stroke
				(width 0.1)
				(type default)
			)
			(layer "F.Fab")
		)
		(fp_line
			(start 0.120396 0.2794)
			(end -0.12065 0.2794)
			(stroke
				(width 0.1)
				(type default)
			)
			(layer "F.Fab")
		)
		(fp_line
			(start 0.120396 0.3048)
			(end 0.120396 0.2794)
			(stroke
				(width 0.1)
				(type default)
			)
			(layer "F.Fab")
		)
		(fp_line
			(start 0.12065 -0.3048)
			(end 0.67945 -0.3048)
			(stroke
				(width 0.1)
				(type default)
			)
			(layer "F.Fab")
		)
		(fp_line
			(start 0.12065 -0.2794)
			(end 0.12065 -0.3048)
			(stroke
				(width 0.1)
				(type default)
			)
			(layer "F.Fab")
		)
		(fp_line
			(start 0.67945 -0.3048)
			(end 0.67945 0.3048)
			(stroke
				(width 0.1)
				(type default)
			)
			(layer "F.Fab")
		)
		(fp_line
			(start 0.67945 0.3048)
			(end 0.120396 0.3048)
			(stroke
				(width 0.1)
				(type default)
			)
			(layer "F.Fab")
		)
		(pad "1" smd circle
			(at -0.40005 0)
			(size 0 0)
			(layers "F.Cu" "F.Mask" "F.Paste")
			(net "PVDDCR_CPU1_P1_VMON")
		)
		(pad "2" smd circle
			(at 0.40005 0)
			(size 0 0)
			(layers "F.Cu" "F.Mask" "F.Paste")
			(net "GND")
		)
	)
	(footprint ""
		(layer "F.Cu")
		(at 12.876784 -392.650726 90)
		(property "Reference" "PR6626"
			(at 0 0 90)
			(layer "F.SilkS")
			(hide yes)
			(effects
				(font
					(size 1.27 1.27)
				)
			)
		)
		(property "Value" ""
			(at 0 0 90)
			(layer "F.Fab")
			(effects
				(font
					(size 1.27 1.27)
				)
			)
		)
		(duplicate_pad_numbers_are_jumpers no)
		(fp_line
			(start 0.7874 -0.4064)
			(end 0.7874 0.4064)
			(stroke
				(width 0.1524)
				(type default)
			)
			(layer "F.SilkS")
		)
		(fp_line
			(start -0.7874 -0.4064)
			(end 0.7874 -0.4064)
			(stroke
				(width 0.1524)
				(type default)
			)
			(layer "F.SilkS")
		)
		(fp_line
			(start -0.7874 -0.202184)
			(end -0.7874 -0.4064)
			(stroke
				(width 0.1524)
				(type default)
			)
			(layer "F.SilkS")
		)
		(fp_line
			(start 0.7874 0.4064)
			(end -0.271526 0.4064)
			(stroke
				(width 0.1524)
				(type default)
			)
			(layer "F.SilkS")
		)
		(fp_line
			(start -0.12065 -0.305054)
			(end -0.12065 -0.2794)
			(stroke
				(width 0.1)
				(type default)
			)
			(layer "F.Fab")
		)
		(fp_line
			(start -0.67945 -0.305054)
			(end -0.12065 -0.305054)
			(stroke
				(width 0.1)
				(type default)
			)
			(layer "F.Fab")
		)
		(fp_line
			(start 0.67945 -0.3048)
			(end 0.67945 0.3048)
			(stroke
				(width 0.1)
				(type default)
			)
			(layer "F.Fab")
		)
		(fp_line
			(start 0.12065 -0.3048)
			(end 0.67945 -0.3048)
			(stroke
				(width 0.1)
				(type default)
			)
			(layer "F.Fab")
		)
		(fp_line
			(start 0.12065 -0.2794)
			(end 0.12065 -0.3048)
			(stroke
				(width 0.1)
				(type default)
			)
			(layer "F.Fab")
		)
		(fp_line
			(start -0.12065 -0.2794)
			(end 0.12065 -0.2794)
			(stroke
				(width 0.1)
				(type default)
			)
			(layer "F.Fab")
		)
		(fp_line
			(start 0.120396 0.2794)
			(end -0.12065 0.2794)
			(stroke
				(width 0.1)
				(type default)
			)
			(layer "F.Fab")
		)
		(fp_line
			(start -0.12065 0.2794)
			(end -0.12065 0.3048)
			(stroke
				(width 0.1)
				(type default)
			)
			(layer "F.Fab")
		)
		(fp_line
			(start 0.67945 0.3048)
			(end 0.120396 0.3048)
			(stroke
				(width 0.1)
				(type default)
			)
			(layer "F.Fab")
		)
		(fp_line
			(start 0.120396 0.3048)
			(end 0.120396 0.2794)
			(stroke
				(width 0.1)
				(type default)
			)
			(layer "F.Fab")
		)
		(fp_line
			(start -0.12065 0.3048)
			(end -0.67945 0.3048)
			(stroke
				(width 0.1)
				(type default)
			)
			(layer "F.Fab")
		)
		(fp_line
			(start -0.67945 0.3048)
			(end -0.67945 -0.305054)
			(stroke
				(width 0.1)
				(type default)
			)
			(layer "F.Fab")
		)
		(pad "1" smd circle
			(at -0.40005 0 90)
			(size 0 0)
			(layers "F.Cu" "F.Mask" "F.Paste")
			(net "P0V9_RETIMER_CPU1_VOS1")
		)
		(pad "2" smd circle
			(at 0.40005 0 90)
			(size 0 0)
			(layers "F.Cu" "F.Mask" "F.Paste")
			(net "P0V9_CPU1_RT_2D")
		)
	)
)
